(kicad_pcb
	(version 20260206)
	(generator "pcbnew")
	(generator_version "10.0")
	(general
		(thickness 1.6)
		(legacy_teardrops no)
	)
	(paper "A4")
	(title_block
		(title "v1-chassis-manager — T6M_CM_d_v01_1031_1645.brd")
		(comment 1 "Open CloudServer (Microsoft) / footprints 897-903 of 2512")
	)
	(layers
		(0 "F.Cu" signal "TOP")
		(4 "In1.Cu" signal "GND1")
		(6 "In2.Cu" signal "IN1")
		(8 "In3.Cu" signal "VCC1")
		(10 "In4.Cu" signal "VCC2")
		(12 "In5.Cu" signal "GND2")
		(14 "In6.Cu" signal "IN2")
		(16 "In7.Cu" signal "IN3")
		(18 "In8.Cu" signal "GND3")
		(2 "B.Cu" signal "BOTTOM")
		(9 "F.Adhes" user "F.Adhesive")
		(11 "B.Adhes" user "B.Adhesive")
		(13 "F.Paste" user "Package Geometry/Pastemask Top")
		(15 "B.Paste" user "Package Geometry/Pastemask Bottom")
		(5 "F.SilkS" user "Ref Des/Silkscreen Top")
		(7 "B.SilkS" user "Ref Des/Silkscreen Bottom")
		(1 "F.Mask" user "Board Geometry/Soldermask Top")
		(3 "B.Mask" user "Board Geometry/Soldermask Bottom")
		(17 "Dwgs.User" user "User.Drawings")
		(19 "Cmts.User" user "User.Comments")
		(21 "Eco1.User" user "User.Eco1")
		(23 "Eco2.User" user "User.Eco2")
		(25 "Edge.Cuts" user "Board Geometry/Outline")
		(27 "Margin" user)
		(31 "F.CrtYd" user "Package Geometry/Place Bound Top")
		(29 "B.CrtYd" user "Package Geometry/Place Bound Bottom")
		(35 "F.Fab" user "Ref Des/Assembly Top")
		(33 "B.Fab" user "Ref Des/Assembly Bottom")
	)
	(footprint ""
		(layer "F.Cu")
		(at 161.632646 -78.363318 90)
		(property "Reference" "U130"
			(at 0.87122 -2.072894 90)
			(unlocked yes)
			(layer "F.SilkS")
			(effects
				(font
					(size 0.7874 0.5842)
					(thickness 0.1524)
				)
				(justify left)
			)
		)
		(property "Value" ""
			(at 0 0 90)
			(layer "F.Fab")
			(effects
				(font
					(size 1.27 1.27)
				)
			)
		)
		(duplicate_pad_numbers_are_jumpers no)
		(fp_line
			(start 0.525018 0.025146)
			(end 0.320802 0.025146)
			(stroke
				(width 0.1524)
				(type default)
			)
			(layer "F.SilkS")
		)
		(fp_line
			(start -2.320798 0.025146)
			(end -2.525014 0.025146)
			(stroke
				(width 0.1524)
				(type default)
			)
			(layer "F.SilkS")
		)
		(fp_line
			(start -2.525014 0.025146)
			(end -2.525014 0.661162)
			(stroke
				(width 0.1524)
				(type default)
			)
			(layer "F.SilkS")
		)
		(fp_line
			(start 0.525018 0.686562)
			(end 0.525018 0.025146)
			(stroke
				(width 0.1524)
				(type default)
			)
			(layer "F.SilkS")
		)
		(fp_line
			(start -2.525014 2.540762)
			(end -2.525014 3.075178)
			(stroke
				(width 0.1524)
				(type default)
			)
			(layer "F.SilkS")
		)
		(fp_line
			(start 0.525018 3.075178)
			(end 0.525018 0.025146)
			(stroke
				(width 0.1524)
				(type default)
			)
			(layer "F.SilkS")
		)
		(fp_line
			(start 0.525018 3.075178)
			(end 0.525018 2.489962)
			(stroke
				(width 0.1524)
				(type default)
			)
			(layer "F.SilkS")
		)
		(fp_line
			(start 0.320802 3.075178)
			(end 0.525018 3.075178)
			(stroke
				(width 0.1524)
				(type default)
			)
			(layer "F.SilkS")
		)
		(fp_line
			(start -2.525014 3.075178)
			(end -2.525014 0.025146)
			(stroke
				(width 0.1524)
				(type default)
			)
			(layer "F.SilkS")
		)
		(fp_line
			(start -2.525014 3.075178)
			(end -2.320798 3.075178)
			(stroke
				(width 0.1524)
				(type default)
			)
			(layer "F.SilkS")
		)
		(fp_poly
			(pts
				(xy 0.106172 -1.266444) (xy 0.406146 -2.16662) (xy -0.193802 -2.16662)
			)
			(stroke
				(width 0)
				(type default)
			)
			(fill yes)
			(layer "F.SilkS")
		)
		(fp_poly
			(pts
				(xy 0.525018 0.025146) (xy 0.244602 0.025146) (xy 0.244602 -0.532638) (xy -2.244598 -0.532638) (xy -2.244598 0.025146)
				(xy -2.525014 0.025146) (xy -2.525014 3.075178) (xy -2.244598 3.075178) (xy -2.244598 3.632962)
				(xy 0.244602 3.632962) (xy 0.244602 3.075178) (xy 0.525018 3.075178)
			)
			(stroke
				(width 0)
				(type default)
			)
			(fill no)
			(layer "F.CrtYd")
		)
		(fp_line
			(start 0.525018 0.025146)
			(end 0.525018 3.075178)
			(stroke
				(width 0.1)
				(type default)
			)
			(layer "F.Fab")
		)
		(fp_line
			(start -2.525014 0.025146)
			(end 0.525018 0.025146)
			(stroke
				(width 0.1)
				(type default)
			)
			(layer "F.Fab")
		)
		(fp_line
			(start 0.525018 3.075178)
			(end -2.525014 3.075178)
			(stroke
				(width 0.1)
				(type default)
			)
			(layer "F.Fab")
		)
		(fp_line
			(start -2.525014 3.075178)
			(end -2.525014 0.025146)
			(stroke
				(width 0.1)
				(type default)
			)
			(layer "F.Fab")
		)
		(fp_poly
			(pts
				(xy 0 -0.519938) (xy 0.302514 -1.427734) (xy -0.302514 -1.427734)
			)
			(stroke
				(width 0)
				(type default)
			)
			(fill yes)
			(layer "F.Fab")
		)
		(fp_text user "1"
			(at 0.677672 -1.741932 0)
			(unlocked yes)
			(layer "F.SilkS")
			(effects
				(font
					(size 0.635 0.4064)
					(thickness 0.1524)
				)
				(justify left)
			)
		)
		(fp_text user "5"
			(at -2.791968 -0.622046 0)
			(unlocked yes)
			(layer "F.SilkS")
			(effects
				(font
					(size 0.635 0.4064)
					(thickness 0.1524)
				)
				(justify left)
			)
		)
		(fp_text user "10"
			(at 0.84074 3.118612 0)
			(unlocked yes)
			(layer "F.SilkS")
			(effects
				(font
					(size 0.635 0.4064)
					(thickness 0.1524)
				)
				(justify left)
			)
		)
		(fp_text user "6"
			(at -2.753868 3.772154 180)
			(unlocked yes)
			(layer "F.SilkS")
			(effects
				(font
					(size 0.635 0.4064)
					(thickness 0.1524)
				)
				(justify left)
			)
		)
		(fp_text user "1"
			(at 0.790702 -0.695706 270)
			(unlocked yes)
			(layer "F.Fab")
			(effects
				(font
					(size 0.7874 0.5842)
					(thickness 0.000001)
				)
				(justify left)
			)
		)
		(fp_text user "5"
			(at -2.155698 -0.695706 270)
			(unlocked yes)
			(layer "F.Fab")
			(effects
				(font
					(size 0.7874 0.5842)
					(thickness 0.000001)
				)
				(justify left)
			)
		)
		(fp_text user "10"
			(at 1.565402 3.700272 270)
			(unlocked yes)
			(layer "F.Fab")
			(effects
				(font
					(size 0.7874 0.5842)
					(thickness 0.000001)
				)
				(justify left)
			)
		)
		(fp_text user "6"
			(at -2.155698 3.725672 270)
			(unlocked yes)
			(layer "F.Fab")
			(effects
				(font
					(size 0.7874 0.5842)
					(thickness 0.000001)
				)
				(justify left)
			)
		)
		(pad "1" smd rect
			(at 0 0 270)
			(size 0.2794 0.9144)
			(layers "F.Cu" "F.Mask" "F.Paste")
			(net "P1V0_NODE1")
		)
		(pad "2" smd rect
			(at -0.499872 0 270)
			(size 0.2794 0.9144)
			(layers "F.Cu" "F.Mask" "F.Paste")
			(net "P1V0_NODE1")
		)
		(pad "3" smd rect
			(at -0.999998 0 270)
			(size 0.2794 0.9144)
			(layers "F.Cu" "F.Mask" "F.Paste")
			(net "P1V0_NODE1")
		)
		(pad "4" smd rect
			(at -1.500124 0 270)
			(size 0.2794 0.9144)
			(layers "F.Cu" "F.Mask" "F.Paste")
			(net "P1V0_ADJ")
		)
		(pad "5" smd rect
			(at -1.999996 0 90)
			(size 0.2794 0.9144)
			(layers "F.Cu" "F.Mask" "F.Paste")
			(net "PWRGD_NODE1_P1V0")
		)
		(pad "6" smd rect
			(at -1.999996 3.100324 90)
			(size 0.2794 0.9144)
			(layers "F.Cu" "F.Mask" "F.Paste")
			(net "N47241340")
		)
		(pad "7" smd rect
			(at -1.500124 3.100324 270)
			(size 0.2794 0.9144)
			(layers "F.Cu" "F.Mask" "F.Paste")
			(net "P1V8_NODE1")
		)
		(pad "8" smd rect
			(at -0.999998 3.100324 270)
			(size 0.2794 0.9144)
			(layers "F.Cu" "F.Mask" "F.Paste")
			(net "P1V8_NODE1")
		)
		(pad "9" smd rect
			(at -0.499872 3.100324 270)
			(size 0.2794 0.9144)
			(layers "F.Cu" "F.Mask" "F.Paste")
			(net "P1V8_NODE1")
		)
		(pad "10" smd rect
			(at 0 3.100324 270)
			(size 0.2794 0.9144)
			(layers "F.Cu" "F.Mask" "F.Paste")
			(net "P5V_STB_NODE1")
		)
		(pad "TH" smd rect
			(at -0.999998 1.550162)
			(size 1.7526 2.667)
			(layers "F.Cu" "F.Mask" "F.Paste")
			(net "GND")
		)
		(zone
			(layer "F.Cu")
			(hatch none 0.5)
			(connect_pads
				(clearance 0)
			)
			(min_thickness 0.25)
			(keepout
				(tracks allowed)
				(vias not_allowed)
				(pads allowed)
				(copperpour not_allowed)
				(footprints allowed)
			)
			(placement
				(enabled no)
				(sheetname "")
			)
			(fill
				(thermal_gap 0.5)
				(thermal_bridge_width 0.5)
				(island_removal_mode 0)
			)
			(polygon
				(pts
					(xy 162.166046 -78.896718) (xy 162.166046 -75.848718) (xy 164.198046 -75.848718) (xy 164.198046 -78.896718)
					(xy 162.267646 -78.896718) (xy 162.267646 -78.769718) (xy 164.121846 -78.769718) (xy 164.121846 -75.950318)
					(xy 162.242246 -75.950318) (xy 162.242246 -78.896718)
				)
			)
		)
	)
	(footprint ""
		(layer "F.Cu")
		(at 38.379654 -114.906298 90)
		(property "Reference" "C849"
			(at 1.549146 1.299718 90)
			(unlocked yes)
			(layer "F.SilkS")
			(effects
				(font
					(size 0.7874 0.5842)
					(thickness 0.1524)
				)
			)
		)
		(property "Value" ""
			(at 0 0 90)
			(layer "F.Fab")
			(effects
				(font
					(size 1.27 1.27)
				)
			)
		)
		(duplicate_pad_numbers_are_jumpers no)
		(fp_line
			(start 1.2954 -0.5842)
			(end 1.2954 0.5842)
			(stroke
				(width 0.1524)
				(type default)
			)
			(layer "F.SilkS")
		)
		(fp_line
			(start 0 -0.5842)
			(end 0 0.5842)
			(stroke
				(width 0.1524)
				(type default)
			)
			(layer "F.SilkS")
		)
		(fp_line
			(start -1.2954 -0.5842)
			(end 1.2954 -0.5842)
			(stroke
				(width 0.1524)
				(type default)
			)
			(layer "F.SilkS")
		)
		(fp_line
			(start 1.2954 0.5842)
			(end -1.2954 0.5842)
			(stroke
				(width 0.1524)
				(type default)
			)
			(layer "F.SilkS")
		)
		(fp_line
			(start -1.2954 0.5842)
			(end -1.2954 -0.5842)
			(stroke
				(width 0.1524)
				(type default)
			)
			(layer "F.SilkS")
		)
		(fp_poly
			(pts
				(xy 0.8636 -0.4572) (xy 0.8636 -0.3556) (xy 1.143 -0.3556) (xy 1.143 0.3556) (xy 0.8636 0.3556)
				(xy 0.8636 0.4572) (xy -0.8636 0.4572) (xy -0.8636 0.3556) (xy -1.143 0.3556) (xy -1.143 -0.3556)
				(xy -0.8636 -0.3556) (xy -0.8636 -0.4572)
			)
			(stroke
				(width 0)
				(type default)
			)
			(fill no)
			(layer "F.CrtYd")
		)
		(fp_line
			(start 0.884936 -0.504952)
			(end 0.884936 0.504952)
			(stroke
				(width 0.1)
				(type default)
			)
			(layer "F.Fab")
		)
		(fp_line
			(start -0.884936 -0.504952)
			(end 0.884936 -0.504952)
			(stroke
				(width 0.1)
				(type default)
			)
			(layer "F.Fab")
		)
		(fp_line
			(start 0.884936 0.504952)
			(end -0.884936 0.504952)
			(stroke
				(width 0.1)
				(type default)
			)
			(layer "F.Fab")
		)
		(fp_line
			(start -0.884936 0.504952)
			(end -0.884936 -0.504952)
			(stroke
				(width 0.1)
				(type default)
			)
			(layer "F.Fab")
		)
		(pad "1" smd rect
			(at 0.7366 0 180)
			(size 0.7112 0.8128)
			(layers "F.Cu" "F.Mask" "F.Paste")
			(net "FM_CPLD_NODE1_P1V5_EN_LV")
		)
		(pad "2" smd rect
			(at -0.7366 0 180)
			(size 0.7112 0.8128)
			(layers "F.Cu" "F.Mask" "F.Paste")
			(net "P1V5_NODE1")
		)
	)
	(footprint ""
		(layer "F.Cu")
		(at 83.67776 -185.205624 -90)
		(property "Reference" "R822"
			(at -4.198112 1.876552 90)
			(unlocked yes)
			(layer "F.SilkS")
			(effects
				(font
					(size 0.7874 0.5842)
					(thickness 0.1524)
				)
				(justify left)
			)
		)
		(property "Value" ""
			(at 0 0 270)
			(layer "F.Fab")
			(effects
				(font
					(size 1.27 1.27)
				)
			)
		)
		(duplicate_pad_numbers_are_jumpers no)
		(fp_line
			(start -0.7874 0.4064)
			(end -0.7874 -0.4064)
			(stroke
				(width 0.1524)
				(type default)
			)
			(layer "F.SilkS")
		)
		(fp_line
			(start 0.7874 0.4064)
			(end -0.7874 0.4064)
			(stroke
				(width 0.1524)
				(type default)
			)
			(layer "F.SilkS")
		)
		(fp_line
			(start -0.7874 -0.4064)
			(end 0.7874 -0.4064)
			(stroke
				(width 0.1524)
				(type default)
			)
			(layer "F.SilkS")
		)
		(fp_line
			(start 0.7874 -0.4064)
			(end 0.7874 0.4064)
			(stroke
				(width 0.1524)
				(type default)
			)
			(layer "F.SilkS")
		)
		(fp_poly
			(pts
				(xy -0.508 0.2794) (xy -0.508 0.2286) (xy -0.635 0.2286) (xy -0.635 -0.254) (xy -0.5334 -0.254)
				(xy -0.5334 -0.2794) (xy 0.5334 -0.2794) (xy 0.5334 -0.254) (xy 0.635 -0.254) (xy 0.635 0.254) (xy 0.5334 0.254)
				(xy 0.5334 0.2794)
			)
			(stroke
				(width 0)
				(type default)
			)
			(fill no)
			(layer "F.CrtYd")
		)
		(pad "1" smd rect
			(at 0.40005 0 270)
			(size 0.4572 0.508)
			(layers "F.Cu" "F.Mask" "F.Paste")
			(net "I2C_PSU2_SDA")
		)
		(pad "2" smd rect
			(at -0.40005 0 270)
			(size 0.4572 0.508)
			(layers "F.Cu" "F.Mask" "F.Paste")
			(net "I2C_PSU2_R_SDA")
		)
	)
	(footprint ""
		(layer "F.Cu")
		(at 90.81262 -177.578512 180)
		(property "Reference" "R809"
			(at -85.97392 -76.287122 0)
			(unlocked yes)
			(layer "F.SilkS")
			(effects
				(font
					(size 0.7874 0.5842)
					(thickness 0.1524)
				)
				(justify left)
			)
		)
		(property "Value" ""
			(at 0 0 180)
			(layer "F.Fab")
			(effects
				(font
					(size 1.27 1.27)
				)
			)
		)
		(duplicate_pad_numbers_are_jumpers no)
		(fp_line
			(start 0.7874 0.4064)
			(end -0.7874 0.4064)
			(stroke
				(width 0.1524)
				(type default)
			)
			(layer "F.SilkS")
		)
		(fp_line
			(start 0.7874 -0.4064)
			(end 0.7874 0.4064)
			(stroke
				(width 0.1524)
				(type default)
			)
			(layer "F.SilkS")
		)
		(fp_line
			(start -0.7874 0.4064)
			(end -0.7874 -0.4064)
			(stroke
				(width 0.1524)
				(type default)
			)
			(layer "F.SilkS")
		)
		(fp_line
			(start -0.7874 -0.4064)
			(end 0.7874 -0.4064)
			(stroke
				(width 0.1524)
				(type default)
			)
			(layer "F.SilkS")
		)
		(fp_poly
			(pts
				(xy -0.508 0.2794) (xy -0.508 0.2286) (xy -0.635 0.2286) (xy -0.635 -0.254) (xy -0.5334 -0.254)
				(xy -0.5334 -0.2794) (xy 0.5334 -0.2794) (xy 0.5334 -0.254) (xy 0.635 -0.254) (xy 0.635 0.254) (xy 0.5334 0.254)
				(xy 0.5334 0.2794)
			)
			(stroke
				(width 0)
				(type default)
			)
			(fill no)
			(layer "F.CrtYd")
		)
		(pad "1" smd rect
			(at 0.40005 0 180)
			(size 0.4572 0.508)
			(layers "F.Cu" "F.Mask" "F.Paste")
			(net "CPLD_UART_RTS_P4_N")
		)
		(pad "2" smd rect
			(at -0.40005 0 180)
			(size 0.4572 0.508)
			(layers "F.Cu" "F.Mask" "F.Paste")
			(net "GND")
		)
	)
	(footprint ""
		(layer "F.Cu")
		(at 149.039326 -41.881044 -90)
		(property "Reference" "R1013"
			(at -0.345948 -10.157968 90)
			(unlocked yes)
			(layer "F.SilkS")
			(effects
				(font
					(size 0.7874 0.5842)
					(thickness 0.1524)
				)
				(justify left)
			)
		)
		(property "Value" ""
			(at 0 0 270)
			(layer "F.Fab")
			(effects
				(font
					(size 1.27 1.27)
				)
			)
		)
		(duplicate_pad_numbers_are_jumpers no)
		(fp_line
			(start -0.7874 0.4064)
			(end -0.7874 -0.4064)
			(stroke
				(width 0.1524)
				(type default)
			)
			(layer "F.SilkS")
		)
		(fp_line
			(start 0.7874 0.4064)
			(end -0.7874 0.4064)
			(stroke
				(width 0.1524)
				(type default)
			)
			(layer "F.SilkS")
		)
		(fp_line
			(start -0.7874 -0.4064)
			(end 0.7874 -0.4064)
			(stroke
				(width 0.1524)
				(type default)
			)
			(layer "F.SilkS")
		)
		(fp_line
			(start 0.7874 -0.4064)
			(end 0.7874 0.4064)
			(stroke
				(width 0.1524)
				(type default)
			)
			(layer "F.SilkS")
		)
		(fp_poly
			(pts
				(xy -0.508 0.2794) (xy -0.508 0.2286) (xy -0.635 0.2286) (xy -0.635 -0.254) (xy -0.5334 -0.254)
				(xy -0.5334 -0.2794) (xy 0.5334 -0.2794) (xy 0.5334 -0.254) (xy 0.635 -0.254) (xy 0.635 0.254) (xy 0.5334 0.254)
				(xy 0.5334 0.2794)
			)
			(stroke
				(width 0)
				(type default)
			)
			(fill no)
			(layer "F.CrtYd")
		)
		(pad "1" smd rect
			(at 0.40005 0 270)
			(size 0.4572 0.508)
			(layers "F.Cu" "F.Mask" "F.Paste")
			(net "GND")
		)
		(pad "2" smd rect
			(at -0.40005 0 270)
			(size 0.4572 0.508)
			(layers "F.Cu" "F.Mask" "F.Paste")
			(net "UART_RTS_P1_N")
		)
	)
	(footprint ""
		(layer "F.Cu")
		(at 110.60176 -185.205624 -90)
		(property "Reference" "R887"
			(at -4.768088 -0.724408 90)
			(unlocked yes)
			(layer "F.SilkS")
			(effects
				(font
					(size 0.7874 0.5842)
					(thickness 0.1524)
				)
				(justify left)
			)
		)
		(property "Value" ""
			(at 0 0 270)
			(layer "F.Fab")
			(effects
				(font
					(size 1.27 1.27)
				)
			)
		)
		(duplicate_pad_numbers_are_jumpers no)
		(fp_line
			(start -0.7874 0.4064)
			(end -0.7874 -0.4064)
			(stroke
				(width 0.1524)
				(type default)
			)
			(layer "F.SilkS")
		)
		(fp_line
			(start 0.7874 0.4064)
			(end -0.7874 0.4064)
			(stroke
				(width 0.1524)
				(type default)
			)
			(layer "F.SilkS")
		)
		(fp_line
			(start -0.7874 -0.4064)
			(end 0.7874 -0.4064)
			(stroke
				(width 0.1524)
				(type default)
			)
			(layer "F.SilkS")
		)
		(fp_line
			(start 0.7874 -0.4064)
			(end 0.7874 0.4064)
			(stroke
				(width 0.1524)
				(type default)
			)
			(layer "F.SilkS")
		)
		(fp_poly
			(pts
				(xy -0.508 0.2794) (xy -0.508 0.2286) (xy -0.635 0.2286) (xy -0.635 -0.254) (xy -0.5334 -0.254)
				(xy -0.5334 -0.2794) (xy 0.5334 -0.2794) (xy 0.5334 -0.254) (xy 0.635 -0.254) (xy 0.635 0.254) (xy 0.5334 0.254)
				(xy 0.5334 0.2794)
			)
			(stroke
				(width 0)
				(type default)
			)
			(fill no)
			(layer "F.CrtYd")
		)
		(pad "1" smd rect
			(at 0.40005 0 270)
			(size 0.4572 0.508)
			(layers "F.Cu" "F.Mask" "F.Paste")
			(net "T6_NODE2_EN")
		)
		(pad "2" smd rect
			(at -0.40005 0 270)
			(size 0.4572 0.508)
			(layers "F.Cu" "F.Mask" "F.Paste")
			(net "T6_NODE2_EN_R")
		)
	)
	(footprint ""
		(layer "F.Cu")
		(at 69.755004 -175.523652)
		(property "Reference" "C583"
			(at -1.652524 1.504188 0)
			(unlocked yes)
			(layer "F.SilkS")
			(effects
				(font
					(size 0.7874 0.5842)
					(thickness 0.1524)
				)
				(justify left)
			)
		)
		(property "Value" ""
			(at 0 0 0)
			(layer "F.Fab")
			(effects
				(font
					(size 1.27 1.27)
				)
			)
		)
		(duplicate_pad_numbers_are_jumpers no)
		(fp_line
			(start -0.7874 -0.4064)
			(end 0.7874 -0.4064)
			(stroke
				(width 0.1524)
				(type default)
			)
			(layer "F.SilkS")
		)
		(fp_line
			(start -0.7874 0.4064)
			(end -0.7874 -0.4064)
			(stroke
				(width 0.1524)
				(type default)
			)
			(layer "F.SilkS")
		)
		(fp_line
			(start 0 0.381)
			(end 0 -0.381)
			(stroke
				(width 0.1524)
				(type default)
			)
			(layer "F.SilkS")
		)
		(fp_line
			(start 0.7874 -0.4064)
			(end 0.7874 0.4064)
			(stroke
				(width 0.1524)
				(type default)
			)
			(layer "F.SilkS")
		)
		(fp_line
			(start 0.7874 0.4064)
			(end -0.7874 0.4064)
			(stroke
				(width 0.1524)
				(type default)
			)
			(layer "F.SilkS")
		)
		(fp_poly
			(pts
				(xy -0.5334 0.254) (xy -0.635 0.254) (xy -0.635 0.2286) (xy -0.635 -0.254) (xy -0.5334 -0.254) (xy -0.5334 -0.2794)
				(xy 0.5334 -0.2794) (xy 0.5334 -0.254) (xy 0.635 -0.254) (xy 0.635 0.254) (xy 0.5334 0.254) (xy 0.5334 0.2794)
				(xy -0.508 0.2794) (xy -0.5334 0.2794)
			)
			(stroke
				(width 0)
				(type default)
			)
			(fill no)
			(layer "F.CrtYd")
		)
		(pad "1" smd rect
			(at 0.40005 0)
			(size 0.4572 0.508)
			(layers "F.Cu" "F.Mask" "F.Paste")
			(net "P3V3_NODE1")
		)
		(pad "2" smd rect
			(at -0.40005 0)
			(size 0.4572 0.508)
			(layers "F.Cu" "F.Mask" "F.Paste")
			(net "GND")
		)
	)
)
